(kicad_pcb
	(version 20241229)
	(generator "pcbnew")
	(generator_version "9.0")
	(general
		(thickness 1.6296)
		(legacy_teardrops no)
	)
	(paper "A3")
	(title_block
		(title "Thunderbolt to 10GbE adapter")
		(date "2026-04-21")
		(rev "1.1.0")
		(company "Antmicro Ltd")
		(comment 1 "www.antmicro.com")
		(comment 9 "footprints 289-289 of 703")
	)
	(layers
		(0 "F.Cu" signal)
		(4 "In1.Cu" signal)
		(6 "In2.Cu" signal)
		(8 "In3.Cu" signal)
		(10 "In4.Cu" signal)
		(12 "In5.Cu" signal)
		(14 "In6.Cu" signal)
		(2 "B.Cu" signal)
		(9 "F.Adhes" user "F.Adhesive")
		(11 "B.Adhes" user "B.Adhesive")
		(13 "F.Paste" user)
		(15 "B.Paste" user)
		(5 "F.SilkS" user "F.Silkscreen")
		(7 "B.SilkS" user "B.Silkscreen")
		(1 "F.Mask" user)
		(3 "B.Mask" user)
		(17 "Dwgs.User" user "User.Drawings")
		(19 "Cmts.User" user "User.Comments")
		(21 "Eco1.User" user "User.Eco1")
		(23 "Eco2.User" user "User.Eco2")
		(25 "Edge.Cuts" user)
		(27 "Margin" user)
		(31 "F.CrtYd" user "F.Courtyard")
		(29 "B.CrtYd" user "B.Courtyard")
		(35 "F.Fab" user)
		(33 "B.Fab" user)
	)
	(footprint "antmicro-footprints:C_0402_1005Metric"
		(layer "F.Cu")
		(at 148.799999 109.850002 90)
		(descr "Capacitor SMD 0402")
		(tags "capacitor SMD 0402")
		(property "Reference" "C128"
			(at -17.049998 14.850002 90)
			(layer "F.SilkS")
			(effects
				(font
					(size 0.7 0.7)
					(thickness 0.15)
				)
			)
		)
		(property "Value" "C_100n_0402"
			(at -1.022927 2.155213 90)
			(layer "F.Fab")
			(effects
				(font
					(size 0.7 0.7)
					(thickness 0.15)
				)
				(justify left bottom)
			)
		)
		(property "Datasheet" "https://www.murata.com/products/productdetail?partno=GRM155R61H104KE14%23"
			(at 0 0 90)
			(layer "F.Fab")
			(hide yes)
			(effects
				(font
					(size 1.27 1.27)
					(thickness 0.15)
				)
			)
		)
		(property "Description" "SMD Multilayer Ceramic Capacitor, 0.1 µF, 50 V, 0402 [1005 Metric], ± 10%, X5R, GRM Series"
			(at 0 0 90)
			(layer "F.Fab")
			(hide yes)
			(effects
				(font
					(size 1.27 1.27)
					(thickness 0.15)
				)
			)
		)
		(property "MPN" "GRM155R61H104KE14D"
			(at 0 0 90)
			(unlocked yes)
			(layer "F.Fab")
			(hide yes)
			(effects
				(font
					(size 1 1)
					(thickness 0.15)
				)
			)
		)
		(property "Manufacturer" "Murata"
			(at 0 0 90)
			(unlocked yes)
			(layer "F.Fab")
			(hide yes)
			(effects
				(font
					(size 1 1)
					(thickness 0.15)
				)
			)
		)
		(property "License" "Apache-2.0"
			(at 0 0 90)
			(unlocked yes)
			(layer "F.Fab")
			(hide yes)
			(effects
				(font
					(size 1 1)
					(thickness 0.15)
				)
			)
		)
		(property "Author" "Antmicro"
			(at 0 0 90)
			(unlocked yes)
			(layer "F.Fab")
			(hide yes)
			(effects
				(font
					(size 1 1)
					(thickness 0.15)
				)
			)
		)
		(property "Val" "100n"
			(at 0 0 90)
			(unlocked yes)
			(layer "F.Fab")
			(hide yes)
			(effects
				(font
					(size 1 1)
					(thickness 0.15)
				)
			)
		)
		(property "Voltage" "50V"
			(at 0 0 90)
			(unlocked yes)
			(layer "F.Fab")
			(hide yes)
			(effects
				(font
					(size 1 1)
					(thickness 0.15)
				)
			)
		)
		(property "Dielectric" "X5R"
			(at 0 0 90)
			(unlocked yes)
			(layer "F.Fab")
			(hide yes)
			(effects
				(font
					(size 1 1)
					(thickness 0.15)
				)
			)
		)
		(sheetname "/X710 DCDC converters/")
		(sheetfile "DCDC_converters_X710.kicad_sch")
		(attr smd)
		(fp_rect
			(start -0.925 -0.47)
			(end 0.925 0.47)
			(stroke
				(width 0.05)
				(type default)
			)
			(fill no)
			(layer "F.CrtYd")
		)
		(fp_line
			(start 0.504 -0.25)
			(end 0.504 0.248)
			(stroke
				(width 0.15)
				(type solid)
			)
			(layer "F.Fab")
		)
		(fp_line
			(start -0.494 -0.25)
			(end 0.504 -0.25)
			(stroke
				(width 0.15)
				(type solid)
			)
			(layer "F.Fab")
		)
		(fp_line
			(start 0.504 0.248)
			(end -0.494 0.248)
			(stroke
				(width 0.15)
				(type solid)
			)
			(layer "F.Fab")
		)
		(fp_line
			(start -0.494 0.248)
			(end -0.494 -0.25)
			(stroke
				(width 0.15)
				(type solid)
			)
			(layer "F.Fab")
		)
		(fp_text user "${REFERENCE}"
			(at -0.939 4.599 90)
			(layer "F.Fab")
			(effects
				(font
					(size 0.7 0.7)
					(thickness 0.15)
				)
				(justify left bottom)
			)
		)
		(fp_text user "Author: Antmicro"
			(at -0.939 3.399 90)
			(layer "F.Fab")
			(effects
				(font
					(size 0.7 0.7)
					(thickness 0.15)
				)
				(justify left bottom)
			)
		)
		(fp_text user "License: Apache-2.0"
			(at -0.939 5.799 90)
			(layer "F.Fab")
			(effects
				(font
					(size 0.7 0.7)
					(thickness 0.15)
				)
				(justify left bottom)
			)
		)
		(pad "1" smd roundrect
			(at -0.48 0 90)
			(size 0.59 0.64)
			(layers "F.Cu" "F.Mask" "F.Paste")
			(roundrect_rratio 0.25)
			(net 332 "/X710 DCDC converters/DVDD_BST")
			(pintype "passive")
		)
		(pad "2" smd roundrect
			(at 0.48 0 90)
			(size 0.59 0.64)
			(layers "F.Cu" "F.Mask" "F.Paste")
			(roundrect_rratio 0.25)
			(net 313 "/X710 DCDC converters/DVDD_SW")
			(pintype "passive")
		)
	)
)
